# T6G (Grand Teton) — schematic netlist excerpt (pin names and nets, part order shuffled) for the footprints in the layout excerpt that follows; sources: Cadence DE-HDL packaged netlist, KiCad conversion of 04192023_DAF0TMB3IC0_F0TG_MB_C_brd_V02_OCP.brd

R6068  Q_RES  0 5% EMPTY  pkg 0402LF  page 151 : A = JTAG_SCM_TDO_R ; B = JTAG_SCM_TDO
C139  Q_CAP  0.1UF 10V 10% X7S  pkg C0201  page 323 : A = P0V9_CPU1_RT_2D ; B = GND
PR199  Q_RES  0 5% CHIP  pkg 0402LF  page 212 : A = PVDDCR_CPU0_P1_VOS3 ; B = PVDDCR_CPU0_P1

(kicad_pcb
	(version 20260206)
	(generator "pcbnew")
	(generator_version "10.0")
	(general
		(thickness 1.6)
		(legacy_teardrops no)
	)
	(paper "A4")
	(title_block
		(title "04192023_DAF0TMB3IC0_F0TG_MB_C_brd_V02_OCP.brd")
		(comment 1 "Grand Teton / footprints 7054-7056 of 8354")
	)
	(layers
		(0 "F.Cu" signal "TOP")
		(4 "In1.Cu" signal "GND")
		(6 "In2.Cu" signal "IN1")
		(8 "In3.Cu" signal "GND1")
		(10 "In4.Cu" signal "IN2")
		(12 "In5.Cu" signal "GND2")
		(14 "In6.Cu" signal "IN3")
		(16 "In7.Cu" signal "GND3")
		(18 "In8.Cu" signal "VCC")
		(20 "In9.Cu" signal "VCC1")
		(22 "In10.Cu" signal "GND4")
		(24 "In11.Cu" signal "IN4")
		(26 "In12.Cu" signal "GND5")
		(28 "In13.Cu" signal "IN5")
		(30 "In14.Cu" signal "GND6")
		(32 "In15.Cu" signal "IN6")
		(34 "In16.Cu" signal "GND7")
		(2 "B.Cu" signal "BOTTOM")
		(9 "F.Adhes" user "F.Adhesive")
		(11 "B.Adhes" user "B.Adhesive")
		(13 "F.Paste" user "Package Geometry/Pastemask Top")
		(15 "B.Paste" user "Package Geometry/Pastemask Bottom")
		(5 "F.SilkS" user "Ref Des/Silkscreen Top")
		(7 "B.SilkS" user "Ref Des/Silkscreen Bottom")
		(1 "F.Mask" user "Board Geometry/Soldermask Top")
		(3 "B.Mask" user "Board Geometry/Soldermask Bottom")
		(17 "Dwgs.User" user "User.Drawings")
		(19 "Cmts.User" user "User.Comments")
		(21 "Eco1.User" user "User.Eco1")
		(23 "Eco2.User" user "User.Eco2")
		(25 "Edge.Cuts" user "Board Geometry/Outline")
		(27 "Margin" user)
		(31 "F.CrtYd" user "Package Geometry/Place Bound Top")
		(29 "B.CrtYd" user "Package Geometry/Place Bound Bottom")
		(35 "F.Fab" user "Ref Des/Assembly Top")
		(33 "B.Fab" user "Ref Des/Assembly Bottom")
	)
	(footprint ""
		(layer "B.Cu")
		(at 154.577288 -9.48055 90)
		(property "Reference" "R6068"
			(at 0 0 90)
			(layer "B.SilkS")
			(hide yes)
			(effects
				(font
					(size 1.27 1.27)
				)
				(justify mirror)
			)
		)
		(property "Value" ""
			(at 0 0 90)
			(layer "B.Fab")
			(effects
				(font
					(size 1.27 1.27)
				)
				(justify mirror)
			)
		)
		(duplicate_pad_numbers_are_jumpers no)
		(fp_line
			(start 0.7874 -0.4064)
			(end -0.7874 -0.4064)
			(stroke
				(width 0.1524)
				(type default)
			)
			(layer "B.SilkS")
		)
		(fp_line
			(start -0.7874 -0.4064)
			(end -0.7874 0.4064)
			(stroke
				(width 0.1524)
				(type default)
			)
			(layer "B.SilkS")
		)
		(fp_line
			(start 0.7874 0.4064)
			(end 0.7874 -0.4064)
			(stroke
				(width 0.1524)
				(type default)
			)
			(layer "B.SilkS")
		)
		(fp_line
			(start -0.7874 0.4064)
			(end 0.7874 0.4064)
			(stroke
				(width 0.1524)
				(type default)
			)
			(layer "B.SilkS")
		)
		(fp_line
			(start 0.67945 -0.305054)
			(end 0.12065 -0.305054)
			(stroke
				(width 0.1)
				(type default)
			)
			(layer "B.Fab")
		)
		(fp_line
			(start 0.12065 -0.305054)
			(end 0.12065 -0.2794)
			(stroke
				(width 0.1)
				(type default)
			)
			(layer "B.Fab")
		)
		(fp_line
			(start -0.12065 -0.3048)
			(end -0.67945 -0.3048)
			(stroke
				(width 0.1)
				(type default)
			)
			(layer "B.Fab")
		)
		(fp_line
			(start -0.67945 -0.3048)
			(end -0.67945 0.3048)
			(stroke
				(width 0.1)
				(type default)
			)
			(layer "B.Fab")
		)
		(fp_line
			(start 0.12065 -0.2794)
			(end -0.12065 -0.2794)
			(stroke
				(width 0.1)
				(type default)
			)
			(layer "B.Fab")
		)
		(fp_line
			(start -0.12065 -0.2794)
			(end -0.12065 -0.3048)
			(stroke
				(width 0.1)
				(type default)
			)
			(layer "B.Fab")
		)
		(fp_line
			(start 0.12065 0.2794)
			(end 0.12065 0.3048)
			(stroke
				(width 0.1)
				(type default)
			)
			(layer "B.Fab")
		)
		(fp_line
			(start -0.120396 0.2794)
			(end 0.12065 0.2794)
			(stroke
				(width 0.1)
				(type default)
			)
			(layer "B.Fab")
		)
		(fp_line
			(start 0.67945 0.3048)
			(end 0.67945 -0.305054)
			(stroke
				(width 0.1)
				(type default)
			)
			(layer "B.Fab")
		)
		(fp_line
			(start 0.12065 0.3048)
			(end 0.67945 0.3048)
			(stroke
				(width 0.1)
				(type default)
			)
			(layer "B.Fab")
		)
		(fp_line
			(start -0.120396 0.3048)
			(end -0.120396 0.2794)
			(stroke
				(width 0.1)
				(type default)
			)
			(layer "B.Fab")
		)
		(fp_line
			(start -0.67945 0.3048)
			(end -0.120396 0.3048)
			(stroke
				(width 0.1)
				(type default)
			)
			(layer "B.Fab")
		)
		(pad "1" smd rect
			(at 0.40005 0 90)
			(size 0.4572 0.508)
			(layers "B.Cu" "B.Mask" "B.Paste")
			(net "JTAG_SCM_TDO_R")
		)
		(pad "2" smd rect
			(at -0.40005 0 90)
			(size 0.4572 0.508)
			(layers "B.Cu" "B.Mask" "B.Paste")
			(net "JTAG_SCM_TDO")
		)
	)
	(footprint ""
		(layer "B.Cu")
		(at 102.73538 -180.027834 90)
		(property "Reference" "PR199"
			(at 0 0 90)
			(layer "B.SilkS")
			(hide yes)
			(effects
				(font
					(size 1.27 1.27)
				)
				(justify mirror)
			)
		)
		(property "Value" ""
			(at 0 0 90)
			(layer "B.Fab")
			(effects
				(font
					(size 1.27 1.27)
				)
				(justify mirror)
			)
		)
		(duplicate_pad_numbers_are_jumpers no)
		(fp_line
			(start 0.7874 -0.4064)
			(end -0.7874 -0.4064)
			(stroke
				(width 0.1524)
				(type default)
			)
			(layer "B.SilkS")
		)
		(fp_line
			(start -0.7874 -0.4064)
			(end -0.7874 0.4064)
			(stroke
				(width 0.1524)
				(type default)
			)
			(layer "B.SilkS")
		)
		(fp_line
			(start 0.7874 0.4064)
			(end 0.7874 -0.4064)
			(stroke
				(width 0.1524)
				(type default)
			)
			(layer "B.SilkS")
		)
		(fp_line
			(start -0.7874 0.4064)
			(end 0.7874 0.4064)
			(stroke
				(width 0.1524)
				(type default)
			)
			(layer "B.SilkS")
		)
		(fp_line
			(start 0.67945 -0.305054)
			(end 0.12065 -0.305054)
			(stroke
				(width 0.1)
				(type default)
			)
			(layer "B.Fab")
		)
		(fp_line
			(start 0.12065 -0.305054)
			(end 0.12065 -0.2794)
			(stroke
				(width 0.1)
				(type default)
			)
			(layer "B.Fab")
		)
		(fp_line
			(start -0.12065 -0.3048)
			(end -0.67945 -0.3048)
			(stroke
				(width 0.1)
				(type default)
			)
			(layer "B.Fab")
		)
		(fp_line
			(start -0.67945 -0.3048)
			(end -0.67945 0.3048)
			(stroke
				(width 0.1)
				(type default)
			)
			(layer "B.Fab")
		)
		(fp_line
			(start 0.12065 -0.2794)
			(end -0.12065 -0.2794)
			(stroke
				(width 0.1)
				(type default)
			)
			(layer "B.Fab")
		)
		(fp_line
			(start -0.12065 -0.2794)
			(end -0.12065 -0.3048)
			(stroke
				(width 0.1)
				(type default)
			)
			(layer "B.Fab")
		)
		(fp_line
			(start 0.12065 0.2794)
			(end 0.12065 0.3048)
			(stroke
				(width 0.1)
				(type default)
			)
			(layer "B.Fab")
		)
		(fp_line
			(start -0.120396 0.2794)
			(end 0.12065 0.2794)
			(stroke
				(width 0.1)
				(type default)
			)
			(layer "B.Fab")
		)
		(fp_line
			(start 0.67945 0.3048)
			(end 0.67945 -0.305054)
			(stroke
				(width 0.1)
				(type default)
			)
			(layer "B.Fab")
		)
		(fp_line
			(start 0.12065 0.3048)
			(end 0.67945 0.3048)
			(stroke
				(width 0.1)
				(type default)
			)
			(layer "B.Fab")
		)
		(fp_line
			(start -0.120396 0.3048)
			(end -0.120396 0.2794)
			(stroke
				(width 0.1)
				(type default)
			)
			(layer "B.Fab")
		)
		(fp_line
			(start -0.67945 0.3048)
			(end -0.120396 0.3048)
			(stroke
				(width 0.1)
				(type default)
			)
			(layer "B.Fab")
		)
		(pad "1" smd circle
			(at 0.40005 0 270)
			(size 0 0)
			(layers "B.Cu" "B.Mask" "B.Paste")
			(net "PVDDCR_CPU0_P1_VOS3")
		)
		(pad "2" smd circle
			(at -0.40005 0 270)
			(size 0 0)
			(layers "B.Cu" "B.Mask" "B.Paste")
			(net "PVDDCR_CPU0_P1")
		)
	)
	(footprint ""
		(layer "B.Cu")
		(at 53.378608 -386.766562 90)
		(property "Reference" "C139"
			(at 0 0 90)
			(layer "B.SilkS")
			(hide yes)
			(effects
				(font
					(size 1.27 1.27)
				)
				(justify mirror)
			)
		)
		(property "Value" ""
			(at 0 0 90)
			(layer "B.Fab")
			(effects
				(font
					(size 1.27 1.27)
				)
				(justify mirror)
			)
		)
		(duplicate_pad_numbers_are_jumpers no)
		(fp_line
			(start 0.299974 -0.150114)
			(end -0.299974 -0.150114)
			(stroke
				(width 0.1)
				(type default)
			)
			(layer "B.Fab")
		)
		(fp_line
			(start -0.299974 -0.150114)
			(end -0.299974 0.150114)
			(stroke
				(width 0.1)
				(type default)
			)
			(layer "B.Fab")
		)
		(fp_line
			(start 0.299974 0.150114)
			(end 0.299974 -0.150114)
			(stroke
				(width 0.1)
				(type default)
			)
			(layer "B.Fab")
		)
		(fp_line
			(start -0.299974 0.150114)
			(end 0.299974 0.150114)
			(stroke
				(width 0.1)
				(type default)
			)
			(layer "B.Fab")
		)
		(pad "1" smd rect
			(at 0.2667 0 270)
			(size 0.3048 0.381)
			(layers "B.Cu" "B.Mask" "B.Paste")
			(net "P0V9_CPU1_RT_2D")
		)
		(pad "2" smd rect
			(at -0.2667 0 270)
			(size 0.3048 0.381)
			(layers "B.Cu" "B.Mask" "B.Paste")
			(net "GND")
		)
	)
)
